# TIMECARD (Time Appliance Project (Time Card)) — schematic netlist excerpt (pin names and nets, part order shuffled) for the footprints in the layout excerpt that follows; sources: Cadence DE-HDL packaged netlist, KiCad conversion of R4006-B0001-02_R01.brd

C196  CAPACITOR  0.1UF 25V 10%  pkg SMC_0402R_H022  page 30 : \1\ = XP1R2V_FPGA ; \2\ = SG
R46  RESISTOR  26.7K 1%  pkg SMC_0402R_H016  page 27 : \1\ = SG ; \2\ = XP12R0V_A_ISET

(kicad_pcb
	(version 20260206)
	(generator "pcbnew")
	(generator_version "10.0")
	(general
		(thickness 1.6)
		(legacy_teardrops no)
	)
	(paper "A4")
	(title_block
		(title "timecard-production-celestica-r4006 — R4006-B0001-02_R01.brd")
		(comment 1 "Time Appliance Project (Time Card) / footprints 478-479 of 1113")
	)
	(layers
		(0 "F.Cu" signal "TOP")
		(4 "In1.Cu" signal "L02_GND1")
		(6 "In2.Cu" signal "L03_SIG1")
		(8 "In3.Cu" signal "L04_GND2")
		(10 "In4.Cu" signal "L05_VCC1")
		(12 "In5.Cu" signal "L06_VCC2")
		(14 "In6.Cu" signal "L07_GND3")
		(16 "In7.Cu" signal "L08_SIG2")
		(18 "In8.Cu" signal "L09_GND4")
		(2 "B.Cu" signal "BOTTOM")
		(9 "F.Adhes" user "F.Adhesive")
		(11 "B.Adhes" user "B.Adhesive")
		(13 "F.Paste" user "Package Geometry/Pastemask Top")
		(15 "B.Paste" user "Package Geometry/Pastemask Bottom")
		(5 "F.SilkS" user "Ref Des/Silkscreen Top")
		(7 "B.SilkS" user "Ref Des/Silkscreen Bottom")
		(1 "F.Mask" user "Board Geometry/Soldermask Top")
		(3 "B.Mask" user "Board Geometry/Soldermask Bottom")
		(17 "Dwgs.User" user "User.Drawings")
		(19 "Cmts.User" user "User.Comments")
		(21 "Eco1.User" user "User.Eco1")
		(23 "Eco2.User" user "User.Eco2")
		(25 "Edge.Cuts" user "Board Geometry/Outline")
		(27 "Margin" user)
		(31 "F.CrtYd" user "Package Geometry/Place Bound Top")
		(29 "B.CrtYd" user "Package Geometry/Place Bound Bottom")
		(35 "F.Fab" user "Ref Des/Assembly Top")
		(33 "B.Fab" user "Ref Des/Assembly Bottom")
	)
	(footprint ""
		(layer "F.Cu")
		(at 145.8214 -95.4278 180)
		(property "Reference" "R46"
			(at -0.127 -8.92937 0)
			(unlocked yes)
			(layer "F.SilkS")
			(effects
				(font
					(size 0.7874 0.5842)
					(thickness 0.1524)
				)
			)
		)
		(property "Value" "VAL*"
			(at 0.02032 2.13233 180)
			(unlocked yes)
			(layer "F.Fab")
			(hide yes)
			(effects
				(font
					(size 0.7874 0.5842)
					(thickness 0.1524)
				)
			)
		)
		(property "Device Type" "RESISTOR-G155-02672-01,26.7K,1%"
			(at 0.008382 1.210564 180)
			(unlocked yes)
			(layer "F.Fab")
			(hide yes)
			(effects
				(font
					(size 0.7874 0.5842)
					(thickness 0.1524)
				)
			)
		)
		(property "User Part Number" "PARTNUM*"
			(at 0.02032 4.024884 180)
			(unlocked yes)
			(layer "Cmts.User")
			(hide yes)
			(effects
				(font
					(size 0.7874 0.5842)
					(thickness 0.1524)
				)
			)
		)
		(property "Tolerance" "TOL*"
			(at 0.044704 3.05435 180)
			(unlocked yes)
			(layer "Cmts.User")
			(hide yes)
			(effects
				(font
					(size 0.7874 0.5842)
					(thickness 0.1524)
				)
			)
		)
		(duplicate_pad_numbers_are_jumpers no)
		(fp_line
			(start 1.143 0.5588)
			(end 1.143 -0.5588)
			(stroke
				(width 0.1)
				(type default)
			)
			(layer "F.SilkS")
		)
		(fp_line
			(start 1.143 -0.5588)
			(end -1.143 -0.5588)
			(stroke
				(width 0.1)
				(type default)
			)
			(layer "F.SilkS")
		)
		(fp_line
			(start -1.143 0.5588)
			(end 1.143 0.5588)
			(stroke
				(width 0.1)
				(type default)
			)
			(layer "F.SilkS")
		)
		(fp_line
			(start -1.143 -0.5588)
			(end -1.143 0.5588)
			(stroke
				(width 0.1)
				(type default)
			)
			(layer "F.SilkS")
		)
		(fp_rect
			(start 1.143 -0.5588)
			(end -1.143 0.5588)
			(stroke
				(width 0)
				(type default)
			)
			(fill no)
			(layer "F.CrtYd")
		)
		(fp_line
			(start 0.508 0.3048)
			(end 0.508 -0.3048)
			(stroke
				(width 0.1)
				(type default)
			)
			(layer "F.Fab")
		)
		(fp_line
			(start 0.508 -0.3048)
			(end -0.508 -0.3048)
			(stroke
				(width 0.1)
				(type default)
			)
			(layer "F.Fab")
		)
		(fp_line
			(start -0.508 0.3048)
			(end 0.508 0.3048)
			(stroke
				(width 0.1)
				(type default)
			)
			(layer "F.Fab")
		)
		(fp_line
			(start -0.508 -0.3048)
			(end -0.508 0.3048)
			(stroke
				(width 0.1)
				(type default)
			)
			(layer "F.Fab")
		)
		(pad "1" smd rect
			(at -0.5334 0 180)
			(size 0.7112 0.6096)
			(layers "F.Cu" "F.Mask" "F.Paste")
			(net "SG")
		)
		(pad "2" smd rect
			(at 0.5334 0 180)
			(size 0.7112 0.6096)
			(layers "F.Cu" "F.Mask" "F.Paste")
			(net "XP12R0V_A_ISET")
		)
		(zone
			(layer "F.Cu")
			(hatch none 0.5)
			(connect_pads
				(clearance 0)
			)
			(min_thickness 0.25)
			(keepout
				(tracks allowed)
				(vias not_allowed)
				(pads allowed)
				(copperpour not_allowed)
				(footprints allowed)
			)
			(placement
				(enabled no)
				(sheetname "")
			)
			(fill
				(thermal_gap 0.5)
				(thermal_bridge_width 0.5)
				(island_removal_mode 0)
			)
			(polygon
				(pts
					(xy 145.7452 -95.123) (xy 145.8976 -95.123) (xy 145.8976 -95.7326) (xy 145.7452 -95.7326)
				)
			)
		)
	)
	(footprint ""
		(layer "F.Cu")
		(at 96.4438 -72.898 90)
		(property "Reference" "C196"
			(at 19.05 -27.82443 90)
			(unlocked yes)
			(layer "F.SilkS")
			(effects
				(font
					(size 0.7874 0.5842)
					(thickness 0.1524)
				)
			)
		)
		(property "Value" "VAL*"
			(at 0.0762 2.067306 90)
			(unlocked yes)
			(layer "F.Fab")
			(hide yes)
			(effects
				(font
					(size 0.7874 0.5842)
					(thickness 0.1524)
				)
			)
		)
		(property "Tolerance" "TOL*"
			(at 0.0762 3.032506 90)
			(unlocked yes)
			(layer "Cmts.User")
			(hide yes)
			(effects
				(font
					(size 0.7874 0.5842)
					(thickness 0.1524)
				)
			)
		)
		(property "User Part Number" "PARTNUM*"
			(at 0.1016 4.023106 90)
			(unlocked yes)
			(layer "Cmts.User")
			(hide yes)
			(effects
				(font
					(size 0.7874 0.5842)
					(thickness 0.1524)
				)
			)
		)
		(property "Device Type" "CAPACITOR-G105-0B104-EK,0.1UF,A"
			(at 0.0508 1.127506 90)
			(unlocked yes)
			(layer "F.Fab")
			(hide yes)
			(effects
				(font
					(size 0.7874 0.5842)
					(thickness 0.1524)
				)
			)
		)
		(duplicate_pad_numbers_are_jumpers no)
		(fp_line
			(start 1.143 -0.5588)
			(end -1.143 -0.5588)
			(stroke
				(width 0.1)
				(type default)
			)
			(layer "F.SilkS")
		)
		(fp_line
			(start -1.143 -0.5588)
			(end -1.143 0.5588)
			(stroke
				(width 0.1)
				(type default)
			)
			(layer "F.SilkS")
		)
		(fp_line
			(start 1.143 0.5588)
			(end 1.143 -0.5588)
			(stroke
				(width 0.1)
				(type default)
			)
			(layer "F.SilkS")
		)
		(fp_line
			(start -1.143 0.5588)
			(end 1.143 0.5588)
			(stroke
				(width 0.1)
				(type default)
			)
			(layer "F.SilkS")
		)
		(fp_rect
			(start 1.143 -0.5588)
			(end -1.143 0.5588)
			(stroke
				(width 0)
				(type default)
			)
			(fill no)
			(layer "F.CrtYd")
		)
		(fp_line
			(start 0.508 -0.3048)
			(end -0.508 -0.3048)
			(stroke
				(width 0.1)
				(type default)
			)
			(layer "F.Fab")
		)
		(fp_line
			(start -0.508 -0.3048)
			(end -0.508 0.3048)
			(stroke
				(width 0.1)
				(type default)
			)
			(layer "F.Fab")
		)
		(fp_line
			(start 0.508 0.3048)
			(end 0.508 -0.3048)
			(stroke
				(width 0.1)
				(type default)
			)
			(layer "F.Fab")
		)
		(fp_line
			(start -0.508 0.3048)
			(end 0.508 0.3048)
			(stroke
				(width 0.1)
				(type default)
			)
			(layer "F.Fab")
		)
		(pad "1" smd rect
			(at -0.5334 0 90)
			(size 0.7112 0.6096)
			(layers "F.Cu" "F.Mask" "F.Paste")
			(net "XP1R2V_FPGA")
		)
		(pad "2" smd rect
			(at 0.5334 0 90)
			(size 0.7112 0.6096)
			(layers "F.Cu" "F.Mask" "F.Paste")
			(net "SG")
		)
		(zone
			(layer "F.Cu")
			(hatch none 0.5)
			(connect_pads
				(clearance 0)
			)
			(min_thickness 0.25)
			(keepout
				(tracks allowed)
				(vias not_allowed)
				(pads allowed)
				(copperpour not_allowed)
				(footprints allowed)
			)
			(placement
				(enabled no)
				(sheetname "")
			)
			(fill
				(thermal_gap 0.5)
				(thermal_bridge_width 0.5)
				(island_removal_mode 0)
			)
			(polygon
				(pts
					(xy 96.139 -72.9742) (xy 96.139 -72.8218) (xy 96.7486 -72.8218) (xy 96.7486 -72.9742)
				)
			)
		)
	)
)
